FILE_TYPE = CONNECTIVITY;
{Allegro Design Entry HDL 17.2-2016 S081 (4005846) 1/11/2022}
"PAGE_NUMBER" = 127;
0"NC";
END.
